# BASEBOARD_FAB2 (Tioga Pass) — schematic netlist excerpt (pin names and nets, part order shuffled) for the footprints in the layout excerpt that follows; sources: Cadence DE-HDL packaged netlist, KiCad conversion of Wiwynn_Tioga_Pass_MB.brd

U2M1  NC7SB3157  IC  pkg SMLF  page 113
  B1  = JTAG_MCP_CPU0_TDI
  GND  = GND
  B0  = JTAG_MCP_CPU1_TDI
  A  = JTAG_MCP_MUX_TDI
  VCC  = P3V3_STBY
  S  = FM_CPU0_CD_PRES

R9U10  RES  0.0 5% CHIP  pkg 0402  page 223 : A = P3V3_STBY ; B = VR_PVDDQ_GHJ_VDD
C5G56  CAP_A  22.0UF 4V 20% X6S  pkg 0603V  page 242 : A = PVDDQ_ABC ; B = GND

(kicad_pcb
	(version 20260206)
	(generator "pcbnew")
	(generator_version "10.0")
	(general
		(thickness 1.6)
		(legacy_teardrops no)
	)
	(paper "A4")
	(title_block
		(title "Wiwynn_Tioga_Pass_MB.brd")
		(comment 1 "Tioga Pass / footprints 3246-3248 of 4770")
	)
	(layers
		(0 "F.Cu" signal "TOP")
		(4 "In1.Cu" signal "L2GND")
		(6 "In2.Cu" signal "L3")
		(8 "In3.Cu" signal "L4GND")
		(10 "In4.Cu" signal "L5")
		(12 "In5.Cu" signal "L6GND")
		(14 "In6.Cu" signal "L7VCC")
		(16 "In7.Cu" signal "L8VCC")
		(18 "In8.Cu" signal "L9GND")
		(20 "In9.Cu" signal "L10")
		(22 "In10.Cu" signal "L11GND")
		(24 "In11.Cu" signal "L12")
		(26 "In12.Cu" signal "L13GND")
		(2 "B.Cu" signal "BOTTOM")
		(9 "F.Adhes" user "F.Adhesive")
		(11 "B.Adhes" user "B.Adhesive")
		(13 "F.Paste" user "Package Geometry/Pastemask Top")
		(15 "B.Paste" user "Package Geometry/Pastemask Bottom")
		(5 "F.SilkS" user "Ref Des/Silkscreen Top")
		(7 "B.SilkS" user "Ref Des/Silkscreen Bottom")
		(1 "F.Mask" user "Board Geometry/Soldermask Top")
		(3 "B.Mask" user "Board Geometry/Soldermask Bottom")
		(17 "Dwgs.User" user "User.Drawings")
		(19 "Cmts.User" user "User.Comments")
		(21 "Eco1.User" user "User.Eco1")
		(23 "Eco2.User" user "User.Eco2")
		(25 "Edge.Cuts" user "Board Geometry/Outline")
		(27 "Margin" user)
		(31 "F.CrtYd" user "Package Geometry/Place Bound Top")
		(29 "B.CrtYd" user "Package Geometry/Place Bound Bottom")
		(35 "F.Fab" user "Ref Des/Assembly Top")
		(33 "B.Fab" user "Ref Des/Assembly Bottom")
	)
	(footprint ""
		(layer "B.Cu")
		(at 276.000464 -3.3528 90)
		(property "Reference" "C5G56"
			(at -1.14681 0.76708 180)
			(unlocked yes)
			(layer "B.SilkS")
			(effects
				(font
					(size 0.7874 0.5842)
					(thickness 0.1524)
				)
				(justify mirror)
			)
		)
		(property "Value" ""
			(at 0 0 90)
			(layer "B.Fab")
			(effects
				(font
					(size 1.27 1.27)
				)
				(justify mirror)
			)
		)
		(duplicate_pad_numbers_are_jumpers no)
		(fp_rect
			(start -0.4953 -0.2032)
			(end 0.4953 1.6002)
			(stroke
				(width 0)
				(type default)
			)
			(fill no)
			(layer "B.CrtYd")
		)
		(fp_line
			(start 0.4953 -0.2032)
			(end -0.4953 -0.2032)
			(stroke
				(width 0.1)
				(type default)
			)
			(layer "B.Fab")
		)
		(fp_line
			(start -0.4953 -0.2032)
			(end -0.4953 1.6002)
			(stroke
				(width 0.1)
				(type default)
			)
			(layer "B.Fab")
		)
		(fp_line
			(start 0.4953 1.6002)
			(end 0.4953 -0.2032)
			(stroke
				(width 0.1)
				(type default)
			)
			(layer "B.Fab")
		)
		(fp_line
			(start -0.4953 1.6002)
			(end 0.4953 1.6002)
			(stroke
				(width 0.1)
				(type default)
			)
			(layer "B.Fab")
		)
		(pad "1" smd rect
			(at 0 0 270)
			(size 0.762 0.889)
			(layers "B.Cu" "B.Mask" "B.Paste")
			(net "PVDDQ_ABC")
		)
		(pad "2" smd rect
			(at 0 1.397 270)
			(size 0.762 0.889)
			(layers "B.Cu" "B.Mask" "B.Paste")
			(net "GND")
		)
		(zone
			(layer "B.Cu")
			(hatch none 0.5)
			(connect_pads
				(clearance 0)
			)
			(min_thickness 0.25)
			(keepout
				(tracks not_allowed)
				(vias allowed)
				(pads allowed)
				(copperpour not_allowed)
				(footprints allowed)
			)
			(placement
				(enabled no)
				(sheetname "")
			)
			(fill
				(thermal_gap 0.5)
				(thermal_bridge_width 0.5)
				(island_removal_mode 0)
			)
			(polygon
				(pts
					(xy 276.444964 -2.9718) (xy 276.952964 -2.9718) (xy 276.952964 -3.7338) (xy 276.444964 -3.7338)
				)
			)
		)
	)
	(footprint ""
		(layer "B.Cu")
		(at 13.921232 4.537456 90)
		(property "Reference" "R9U10"
			(at 0 0 90)
			(layer "B.SilkS")
			(hide yes)
			(effects
				(font
					(size 1.27 1.27)
				)
				(justify mirror)
			)
		)
		(property "Value" ""
			(at 0 0 90)
			(layer "B.Fab")
			(effects
				(font
					(size 1.27 1.27)
				)
				(justify mirror)
			)
		)
		(duplicate_pad_numbers_are_jumpers no)
		(fp_rect
			(start -0.2794 0.9906)
			(end 0.2794 -0.1016)
			(stroke
				(width 0)
				(type default)
			)
			(fill no)
			(layer "B.CrtYd")
		)
		(fp_line
			(start 0.2794 -0.1016)
			(end 0.2794 0.9906)
			(stroke
				(width 0.1)
				(type default)
			)
			(layer "B.Fab")
		)
		(fp_line
			(start -0.2794 -0.1016)
			(end 0.2794 -0.1016)
			(stroke
				(width 0.1)
				(type default)
			)
			(layer "B.Fab")
		)
		(fp_line
			(start 0.2794 0.9906)
			(end -0.2794 0.9906)
			(stroke
				(width 0.1)
				(type default)
			)
			(layer "B.Fab")
		)
		(fp_line
			(start -0.2794 0.9906)
			(end -0.2794 -0.1016)
			(stroke
				(width 0.1)
				(type default)
			)
			(layer "B.Fab")
		)
		(pad "1" smd rect
			(at 0 0 270)
			(size 0.508 0.508)
			(layers "B.Cu" "B.Mask" "B.Paste")
			(net "P3V3_STBY")
		)
		(pad "2" smd rect
			(at 0 0.889 270)
			(size 0.508 0.508)
			(layers "B.Cu" "B.Mask" "B.Paste")
			(net "VR_PVDDQ_GHJ_VDD")
		)
		(zone
			(layer "B.Cu")
			(hatch none 0.5)
			(connect_pads
				(clearance 0)
			)
			(min_thickness 0.25)
			(keepout
				(tracks allowed)
				(vias not_allowed)
				(pads allowed)
				(copperpour not_allowed)
				(footprints allowed)
			)
			(placement
				(enabled no)
				(sheetname "")
			)
			(fill
				(thermal_gap 0.5)
				(thermal_bridge_width 0.5)
				(island_removal_mode 0)
			)
			(polygon
				(pts
					(xy 14.556232 4.791456) (xy 14.556232 4.283456) (xy 14.175232 4.283456) (xy 14.175232 4.791456)
				)
			)
		)
		(zone
			(layer "B.Cu")
			(hatch none 0.5)
			(connect_pads
				(clearance 0)
			)
			(min_thickness 0.25)
			(keepout
				(tracks not_allowed)
				(vias allowed)
				(pads allowed)
				(copperpour not_allowed)
				(footprints allowed)
			)
			(placement
				(enabled no)
				(sheetname "")
			)
			(fill
				(thermal_gap 0.5)
				(thermal_bridge_width 0.5)
				(island_removal_mode 0)
			)
			(polygon
				(pts
					(xy 14.556232 4.791456) (xy 14.556232 4.283456) (xy 14.175232 4.283456) (xy 14.175232 4.791456)
				)
			)
		)
	)
	(footprint ""
		(layer "B.Cu")
		(at 445.2366 -128.7272 180)
		(property "Reference" "U2M1"
			(at -3.48742 -1.08331 0)
			(unlocked yes)
			(layer "B.SilkS")
			(effects
				(font
					(size 0.7874 0.5842)
					(thickness 0.1524)
				)
				(justify left mirror)
			)
		)
		(property "Value" ""
			(at 0 0 0)
			(layer "B.Fab")
			(effects
				(font
					(size 1.27 1.27)
				)
				(justify mirror)
			)
		)
		(duplicate_pad_numbers_are_jumpers no)
		(fp_circle
			(center 0.848614 -0.6477)
			(end 0.721614 -0.6477)
			(stroke
				(width 0.254)
				(type default)
			)
			(fill no)
			(layer "B.SilkS")
		)
		(fp_poly
			(pts
				(xy -0.21463 -0.450088) (xy -1.56337 -0.450088) (xy -1.56337 1.75006) (xy -0.21463 1.75006)
			)
			(stroke
				(width 0)
				(type default)
			)
			(fill no)
			(layer "B.CrtYd")
		)
		(fp_line
			(start -0.21463 1.75006)
			(end -0.21463 -0.450088)
			(stroke
				(width 0.1)
				(type default)
			)
			(layer "B.Fab")
		)
		(fp_line
			(start -0.21463 -0.450088)
			(end -1.56337 -0.450088)
			(stroke
				(width 0.1)
				(type default)
			)
			(layer "B.Fab")
		)
		(fp_line
			(start -1.56337 1.75006)
			(end -0.21463 1.75006)
			(stroke
				(width 0.1)
				(type default)
			)
			(layer "B.Fab")
		)
		(fp_line
			(start -1.56337 -0.450088)
			(end -1.56337 1.75006)
			(stroke
				(width 0.1)
				(type default)
			)
			(layer "B.Fab")
		)
		(fp_circle
			(center 0.848614 -0.6477)
			(end 0.721614 -0.6477)
			(stroke
				(width 0.254)
				(type default)
			)
			(fill no)
			(layer "B.Fab")
		)
		(pad "1" smd rect
			(at 0 0)
			(size 1.016 0.381)
			(layers "B.Cu" "B.Mask" "B.Paste")
			(net "JTAG_MCP_CPU0_TDI")
		)
		(pad "2" smd rect
			(at 0 0.649986)
			(size 1.016 0.381)
			(layers "B.Cu" "B.Mask" "B.Paste")
			(net "GND")
		)
		(pad "3" smd rect
			(at 0 1.299972)
			(size 1.016 0.381)
			(layers "B.Cu" "B.Mask" "B.Paste")
			(net "JTAG_MCP_CPU1_TDI")
		)
		(pad "4" smd rect
			(at -1.778 1.299972)
			(size 1.016 0.381)
			(layers "B.Cu" "B.Mask" "B.Paste")
			(net "JTAG_MCP_MUX_TDI")
		)
		(pad "5" smd rect
			(at -1.778 0.649986)
			(size 1.016 0.381)
			(layers "B.Cu" "B.Mask" "B.Paste")
			(net "P3V3_STBY")
		)
		(pad "6" smd rect
			(at -1.778 0)
			(size 1.016 0.381)
			(layers "B.Cu" "B.Mask" "B.Paste")
			(net "FM_CPU0_CD_PRES")
		)
	)
)
